# S9S_MB_2U (Grand Teton) — schematic netlist excerpt (pin names and nets, part order shuffled) for the footprints in the layout excerpt that follows; sources: Cadence DE-HDL packaged netlist, KiCad conversion of 03242023_DA0F0TMBIJ0_F0T_Motherboard_J_brd_V01_OCP.brd

PC262_P0_6  Q_CAP  22UF 16V 20% X6S  pkg C0805  page 269 : A = SW_P12V_PVCCIN_CPU0_FLT ; B = GND
C87  Q_CAP  2.2UF 6.3V 20% X6S  pkg C0402  page 108 : A = P3V3_AUX ; B = GND
PC196_P0_2  Q_CAP  22UF 16V 20% X6S  pkg C0805  page 275 : A = SW_P12V_PVCCINFAON_CPU0_FLT ; B = GND

(kicad_pcb
	(version 20260206)
	(generator "pcbnew")
	(generator_version "10.0")
	(general
		(thickness 1.6)
		(legacy_teardrops no)
	)
	(paper "A4")
	(title_block
		(title "03242023_DA0F0TMBIJ0_F0T_Motherboard_J_brd_V01_OCP.brd")
		(comment 1 "Grand Teton / footprints 5170-5172 of 6105")
	)
	(layers
		(0 "F.Cu" signal "TOP")
		(4 "In1.Cu" signal "GND")
		(6 "In2.Cu" signal "IN1")
		(8 "In3.Cu" signal "GND1")
		(10 "In4.Cu" signal "IN2")
		(12 "In5.Cu" signal "GND2")
		(14 "In6.Cu" signal "IN3")
		(16 "In7.Cu" signal "GND3")
		(18 "In8.Cu" signal "VCC")
		(20 "In9.Cu" signal "VCC1")
		(22 "In10.Cu" signal "GND4")
		(24 "In11.Cu" signal "IN4")
		(26 "In12.Cu" signal "GND5")
		(28 "In13.Cu" signal "IN5")
		(30 "In14.Cu" signal "GND6")
		(32 "In15.Cu" signal "IN6")
		(34 "In16.Cu" signal "GND7")
		(2 "B.Cu" signal "BOTTOM")
		(9 "F.Adhes" user "F.Adhesive")
		(11 "B.Adhes" user "B.Adhesive")
		(13 "F.Paste" user "Package Geometry/Pastemask Top")
		(15 "B.Paste" user "Package Geometry/Pastemask Bottom")
		(5 "F.SilkS" user "Ref Des/Silkscreen Top")
		(7 "B.SilkS" user "Ref Des/Silkscreen Bottom")
		(1 "F.Mask" user "Board Geometry/Soldermask Top")
		(3 "B.Mask" user "Board Geometry/Soldermask Bottom")
		(17 "Dwgs.User" user "User.Drawings")
		(19 "Cmts.User" user "User.Comments")
		(21 "Eco1.User" user "User.Eco1")
		(23 "Eco2.User" user "User.Eco2")
		(25 "Edge.Cuts" user "Board Geometry/Outline")
		(27 "Margin" user)
		(31 "F.CrtYd" user "Package Geometry/Place Bound Top")
		(29 "B.CrtYd" user "Package Geometry/Place Bound Bottom")
		(35 "F.Fab" user "Ref Des/Assembly Top")
		(33 "B.Fab" user "Ref Des/Assembly Bottom")
	)
	(footprint ""
		(layer "B.Cu")
		(at 416.02914 -176.20107)
		(property "Reference" "PC196_P0_2"
			(at 0 0 0)
			(layer "B.SilkS")
			(hide yes)
			(effects
				(font
					(size 1.27 1.27)
				)
				(justify mirror)
			)
		)
		(property "Value" ""
			(at 0 0 0)
			(layer "B.Fab")
			(effects
				(font
					(size 1.27 1.27)
				)
				(justify mirror)
			)
		)
		(duplicate_pad_numbers_are_jumpers no)
		(fp_line
			(start -1.524 -0.762)
			(end -1.524 0.762)
			(stroke
				(width 0.1524)
				(type default)
			)
			(layer "B.SilkS")
		)
		(fp_line
			(start -1.524 0.762)
			(end 1.524 0.762)
			(stroke
				(width 0.1524)
				(type default)
			)
			(layer "B.SilkS")
		)
		(fp_line
			(start 1.524 -0.762)
			(end -1.524 -0.762)
			(stroke
				(width 0.1524)
				(type default)
			)
			(layer "B.SilkS")
		)
		(fp_line
			(start 1.524 0.762)
			(end 1.524 -0.762)
			(stroke
				(width 0.1524)
				(type default)
			)
			(layer "B.SilkS")
		)
		(fp_line
			(start -1.1049 -0.724916)
			(end 1.1049 -0.724916)
			(stroke
				(width 0.1)
				(type default)
			)
			(layer "B.Fab")
		)
		(fp_line
			(start -1.1049 0.724916)
			(end -1.1049 -0.724916)
			(stroke
				(width 0.1)
				(type default)
			)
			(layer "B.Fab")
		)
		(fp_line
			(start 1.1049 -0.724916)
			(end 1.1049 0.724916)
			(stroke
				(width 0.1)
				(type default)
			)
			(layer "B.Fab")
		)
		(fp_line
			(start 1.1049 0.724916)
			(end -1.1049 0.724916)
			(stroke
				(width 0.1)
				(type default)
			)
			(layer "B.Fab")
		)
		(pad "1" smd rect
			(at 0.889 0)
			(size 1.016 1.27)
			(layers "B.Cu" "B.Mask" "B.Paste")
			(net "SW_P12V_PVCCINFAON_CPU0_FLT")
		)
		(pad "2" smd rect
			(at -0.889 0)
			(size 1.016 1.27)
			(layers "B.Cu" "B.Mask" "B.Paste")
			(net "GND")
		)
	)
	(footprint ""
		(layer "B.Cu")
		(at 337.89874 -337.145884 90)
		(property "Reference" "PC262_P0_6"
			(at 0 0 90)
			(layer "B.SilkS")
			(hide yes)
			(effects
				(font
					(size 1.27 1.27)
				)
				(justify mirror)
			)
		)
		(property "Value" ""
			(at 0 0 90)
			(layer "B.Fab")
			(effects
				(font
					(size 1.27 1.27)
				)
				(justify mirror)
			)
		)
		(duplicate_pad_numbers_are_jumpers no)
		(fp_line
			(start 1.524 -0.762)
			(end -1.524 -0.762)
			(stroke
				(width 0.1524)
				(type default)
			)
			(layer "B.SilkS")
		)
		(fp_line
			(start -1.524 -0.762)
			(end -1.524 0.762)
			(stroke
				(width 0.1524)
				(type default)
			)
			(layer "B.SilkS")
		)
		(fp_line
			(start 1.524 0.762)
			(end 1.524 -0.762)
			(stroke
				(width 0.1524)
				(type default)
			)
			(layer "B.SilkS")
		)
		(fp_line
			(start -1.524 0.762)
			(end 1.524 0.762)
			(stroke
				(width 0.1524)
				(type default)
			)
			(layer "B.SilkS")
		)
		(fp_line
			(start 1.1049 -0.724916)
			(end 1.1049 0.724916)
			(stroke
				(width 0.1)
				(type default)
			)
			(layer "B.Fab")
		)
		(fp_line
			(start -1.1049 -0.724916)
			(end 1.1049 -0.724916)
			(stroke
				(width 0.1)
				(type default)
			)
			(layer "B.Fab")
		)
		(fp_line
			(start 1.1049 0.724916)
			(end -1.1049 0.724916)
			(stroke
				(width 0.1)
				(type default)
			)
			(layer "B.Fab")
		)
		(fp_line
			(start -1.1049 0.724916)
			(end -1.1049 -0.724916)
			(stroke
				(width 0.1)
				(type default)
			)
			(layer "B.Fab")
		)
		(pad "1" smd rect
			(at 0.889 0 90)
			(size 1.016 1.27)
			(layers "B.Cu" "B.Mask" "B.Paste")
			(net "SW_P12V_PVCCIN_CPU0_FLT")
		)
		(pad "2" smd rect
			(at -0.889 0 90)
			(size 1.016 1.27)
			(layers "B.Cu" "B.Mask" "B.Paste")
			(net "GND")
		)
	)
	(footprint ""
		(layer "B.Cu")
		(at 181.457346 -319.268856 180)
		(property "Reference" "C87"
			(at 0 0 0)
			(layer "B.SilkS")
			(hide yes)
			(effects
				(font
					(size 1.27 1.27)
				)
				(justify mirror)
			)
		)
		(property "Value" ""
			(at 0 0 0)
			(layer "B.Fab")
			(effects
				(font
					(size 1.27 1.27)
				)
				(justify mirror)
			)
		)
		(duplicate_pad_numbers_are_jumpers no)
		(fp_line
			(start 0.7874 0.4064)
			(end 0.7874 -0.4064)
			(stroke
				(width 0.1524)
				(type default)
			)
			(layer "B.SilkS")
		)
		(fp_line
			(start 0.7874 -0.4064)
			(end -0.7874 -0.4064)
			(stroke
				(width 0.1524)
				(type default)
			)
			(layer "B.SilkS")
		)
		(fp_line
			(start -0.7874 0.4064)
			(end 0.7874 0.4064)
			(stroke
				(width 0.1524)
				(type default)
			)
			(layer "B.SilkS")
		)
		(fp_line
			(start -0.7874 -0.4064)
			(end -0.7874 0.4064)
			(stroke
				(width 0.1524)
				(type default)
			)
			(layer "B.SilkS")
		)
		(fp_line
			(start 0.67945 0.3048)
			(end 0.67945 -0.305054)
			(stroke
				(width 0.1)
				(type default)
			)
			(layer "B.Fab")
		)
		(fp_line
			(start 0.67945 -0.305054)
			(end 0.12065 -0.305054)
			(stroke
				(width 0.1)
				(type default)
			)
			(layer "B.Fab")
		)
		(fp_line
			(start 0.12065 0.3048)
			(end 0.67945 0.3048)
			(stroke
				(width 0.1)
				(type default)
			)
			(layer "B.Fab")
		)
		(fp_line
			(start 0.12065 0.2794)
			(end 0.12065 0.3048)
			(stroke
				(width 0.1)
				(type default)
			)
			(layer "B.Fab")
		)
		(fp_line
			(start 0.12065 -0.2794)
			(end -0.12065 -0.2794)
			(stroke
				(width 0.1)
				(type default)
			)
			(layer "B.Fab")
		)
		(fp_line
			(start 0.12065 -0.305054)
			(end 0.12065 -0.2794)
			(stroke
				(width 0.1)
				(type default)
			)
			(layer "B.Fab")
		)
		(fp_line
			(start -0.120396 0.3048)
			(end -0.120396 0.2794)
			(stroke
				(width 0.1)
				(type default)
			)
			(layer "B.Fab")
		)
		(fp_line
			(start -0.120396 0.2794)
			(end 0.12065 0.2794)
			(stroke
				(width 0.1)
				(type default)
			)
			(layer "B.Fab")
		)
		(fp_line
			(start -0.12065 -0.2794)
			(end -0.12065 -0.3048)
			(stroke
				(width 0.1)
				(type default)
			)
			(layer "B.Fab")
		)
		(fp_line
			(start -0.12065 -0.3048)
			(end -0.67945 -0.3048)
			(stroke
				(width 0.1)
				(type default)
			)
			(layer "B.Fab")
		)
		(fp_line
			(start -0.67945 0.3048)
			(end -0.120396 0.3048)
			(stroke
				(width 0.1)
				(type default)
			)
			(layer "B.Fab")
		)
		(fp_line
			(start -0.67945 -0.3048)
			(end -0.67945 0.3048)
			(stroke
				(width 0.1)
				(type default)
			)
			(layer "B.Fab")
		)
		(pad "1" smd circle
			(at 0.40005 0)
			(size 0 0)
			(layers "B.Cu" "B.Mask" "B.Paste")
			(net "P3V3_AUX")
		)
		(pad "2" smd circle
			(at -0.40005 0)
			(size 0 0)
			(layers "B.Cu" "B.Mask" "B.Paste")
			(net "GND")
		)
	)
)
